(kicad_pcb
	(version 20260206)
	(generator "pcbnew")
	(generator_version "10.0")
	(general
		(thickness 1.6)
		(legacy_teardrops no)
	)
	(paper "A4")
	(title_block
		(title "01162023_DA0F0TEBIF0_F0T_Expander_BD_F_brd_V02_OCP.brd")
		(comment 1 "Grand Teton / footprints 961-966 of 9728")
	)
	(layers
		(0 "F.Cu" signal "TOP")
		(4 "In1.Cu" signal "GND")
		(6 "In2.Cu" signal "VCC")
		(8 "In3.Cu" signal "VCC1")
		(10 "In4.Cu" signal "GND1")
		(12 "In5.Cu" signal "IN1")
		(14 "In6.Cu" signal "GND2")
		(16 "In7.Cu" signal "IN2")
		(18 "In8.Cu" signal "GND3")
		(20 "In9.Cu" signal "IN3")
		(22 "In10.Cu" signal "GND4")
		(24 "In11.Cu" signal "IN4")
		(26 "In12.Cu" signal "GND5")
		(28 "In13.Cu" signal "IN5")
		(30 "In14.Cu" signal "GND6")
		(32 "In15.Cu" signal "IN6")
		(34 "In16.Cu" signal "GND7")
		(2 "B.Cu" signal "BOTTOM")
		(9 "F.Adhes" user "F.Adhesive")
		(11 "B.Adhes" user "B.Adhesive")
		(13 "F.Paste" user "Package Geometry/Pastemask Top")
		(15 "B.Paste" user "Package Geometry/Pastemask Bottom")
		(5 "F.SilkS" user "Ref Des/Silkscreen Top")
		(7 "B.SilkS" user "Ref Des/Silkscreen Bottom")
		(1 "F.Mask" user "Board Geometry/Soldermask Top")
		(3 "B.Mask" user "Board Geometry/Soldermask Bottom")
		(17 "Dwgs.User" user "User.Drawings")
		(19 "Cmts.User" user "User.Comments")
		(21 "Eco1.User" user "User.Eco1")
		(23 "Eco2.User" user "User.Eco2")
		(25 "Edge.Cuts" user "Board Geometry/Outline")
		(27 "Margin" user)
		(31 "F.CrtYd" user "Package Geometry/Place Bound Top")
		(29 "B.CrtYd" user "Package Geometry/Place Bound Bottom")
		(35 "F.Fab" user "Ref Des/Assembly Top")
		(33 "B.Fab" user "Ref Des/Assembly Bottom")
	)
	(footprint ""
		(layer "F.Cu")
		(at 32.890968 -55.663846 90)
		(property "Reference" "PU56"
			(at -1.414018 3.158998 90)
			(unlocked yes)
			(layer "F.SilkS")
			(effects
				(font
					(size 0.7874 0.5842)
					(thickness 0.1524)
				)
				(justify left)
			)
		)
		(property "Value" ""
			(at 0 0 90)
			(layer "F.Fab")
			(effects
				(font
					(size 1.27 1.27)
				)
			)
		)
		(duplicate_pad_numbers_are_jumpers no)
		(fp_line
			(start 1.943608 -1.549908)
			(end 1.943608 1.549908)
			(stroke
				(width 0.1524)
				(type default)
			)
			(layer "F.SilkS")
		)
		(fp_line
			(start -1.943608 -1.549908)
			(end 1.943608 -1.549908)
			(stroke
				(width 0.1524)
				(type default)
			)
			(layer "F.SilkS")
		)
		(fp_line
			(start 1.943608 1.549908)
			(end -1.943608 1.549908)
			(stroke
				(width 0.1524)
				(type default)
			)
			(layer "F.SilkS")
		)
		(fp_line
			(start -1.943608 1.549908)
			(end -1.943608 -1.549908)
			(stroke
				(width 0.1524)
				(type default)
			)
			(layer "F.SilkS")
		)
		(fp_poly
			(pts
				(xy -2.019808 -1.549908) (xy -1.257808 -1.549908) (xy -1.257808 -1.880108) (xy -2.019808 -1.880108)
			)
			(stroke
				(width 0)
				(type default)
			)
			(fill yes)
			(layer "F.SilkS")
		)
		(fp_line
			(start 1.549908 -1.549908)
			(end 1.549908 1.549908)
			(stroke
				(width 0.1)
				(type default)
			)
			(layer "F.Fab")
		)
		(fp_line
			(start -1.549908 -1.549908)
			(end 1.549908 -1.549908)
			(stroke
				(width 0.1)
				(type default)
			)
			(layer "F.Fab")
		)
		(fp_line
			(start 1.549908 1.549908)
			(end -1.549908 1.549908)
			(stroke
				(width 0.1)
				(type default)
			)
			(layer "F.Fab")
		)
		(fp_line
			(start -1.549908 1.549908)
			(end -1.549908 -1.549908)
			(stroke
				(width 0.1)
				(type default)
			)
			(layer "F.Fab")
		)
		(fp_poly
			(pts
				(xy -2.019808 -1.549908) (xy -1.257808 -1.549908) (xy -1.257808 -1.880108) (xy -2.019808 -1.880108)
			)
			(stroke
				(width 0)
				(type default)
			)
			(fill yes)
			(layer "F.Fab")
		)
		(pad "1" smd rect
			(at -1.500124 -1.249934)
			(size 0.2794 0.6096)
			(layers "F.Cu" "F.Mask" "F.Paste")
			(net "P3V3_SSD1")
		)
		(pad "2" smd rect
			(at -1.500124 -0.750062)
			(size 0.2794 0.6096)
			(layers "F.Cu" "F.Mask" "F.Paste")
			(net "P3V3_SSD1")
		)
		(pad "3" smd rect
			(at -1.500124 -0.249936)
			(size 0.2794 0.6096)
			(layers "F.Cu" "F.Mask" "F.Paste")
			(net "P3V3_SSD1")
		)
		(pad "4" smd rect
			(at -1.500124 0.249936)
			(size 0.2794 0.6096)
			(layers "F.Cu" "F.Mask" "F.Paste")
			(net "P3V3_SSD1")
		)
		(pad "5" smd rect
			(at -1.500124 0.750062)
			(size 0.2794 0.6096)
			(layers "F.Cu" "F.Mask" "F.Paste")
			(net "P3V3_SSD1")
		)
		(pad "6" smd rect
			(at -1.500124 1.249934)
			(size 0.2794 0.6096)
			(layers "F.Cu" "F.Mask" "F.Paste")
			(net "GND")
		)
		(pad "7" smd rect
			(at 1.500124 1.249934)
			(size 0.2794 0.6096)
			(layers "F.Cu" "F.Mask" "F.Paste")
			(net "P3V3_SSD1_SS")
		)
		(pad "8" smd rect
			(at 1.500124 0.750062)
			(size 0.2794 0.6096)
			(layers "F.Cu" "F.Mask" "F.Paste")
			(net "PWRGD_P3V3_SSD1")
		)
		(pad "9" smd rect
			(at 1.500124 0.249936)
			(size 0.2794 0.6096)
			(layers "F.Cu" "F.Mask" "F.Paste")
			(net "P3V3_SSD1_OCP")
		)
		(pad "10" smd rect
			(at 1.500124 -0.249936)
			(size 0.2794 0.6096)
			(layers "F.Cu" "F.Mask" "F.Paste")
			(net "P5V_AUX")
		)
		(pad "11" smd rect
			(at 1.500124 -0.750062)
			(size 0.2794 0.6096)
			(layers "F.Cu" "F.Mask" "F.Paste")
			(net "SSD1_AUX_P3V3_EN_R")
		)
		(pad "12" smd rect
			(at 1.500124 -1.249934)
			(size 0.2794 0.6096)
			(layers "F.Cu" "F.Mask" "F.Paste")
			(net "P3V3_AUX")
		)
		(pad "13" smd rect
			(at 0 0 90)
			(size 1.9812 2.7178)
			(layers "F.Cu" "F.Mask" "F.Paste")
			(net "P3V3_AUX")
		)
		(zone
			(layer "F.Cu")
			(hatch none 0.5)
			(connect_pads
				(clearance 0)
			)
			(min_thickness 0.25)
			(keepout
				(tracks not_allowed)
				(vias allowed)
				(pads allowed)
				(copperpour not_allowed)
				(footprints allowed)
			)
			(placement
				(enabled no)
				(sheetname "")
			)
			(fill
				(thermal_gap 0.5)
				(thermal_bridge_width 0.5)
				(island_removal_mode 0)
			)
			(polygon
				(pts
					(xy 31.341568 -56.806846) (xy 31.468568 -56.806846) (xy 34.440368 -56.806846) (xy 34.440876 -56.806846)
					(xy 34.440876 -54.520846) (xy 34.440368 -54.520846) (xy 34.313368 -54.520846) (xy 32.890968 -54.520846)
					(xy 32.890968 -54.622446) (xy 34.313368 -54.622446) (xy 34.313368 -56.705246) (xy 31.468568 -56.705246)
					(xy 31.468568 -54.622446) (xy 32.865568 -54.622446) (xy 32.865568 -54.520846) (xy 31.468568 -54.520846)
					(xy 31.341568 -54.520846) (xy 31.34106 -54.520846) (xy 31.34106 -56.806846)
				)
			)
		)
	)
	(footprint ""
		(layer "F.Cu")
		(at 420.73449 -30.03169 180)
		(property "Reference" "C719"
			(at 0 0 180)
			(layer "F.SilkS")
			(hide yes)
			(effects
				(font
					(size 1.27 1.27)
				)
			)
		)
		(property "Value" ""
			(at 0 0 180)
			(layer "F.Fab")
			(effects
				(font
					(size 1.27 1.27)
				)
			)
		)
		(duplicate_pad_numbers_are_jumpers no)
		(fp_line
			(start 0.299974 0.150114)
			(end -0.299974 0.150114)
			(stroke
				(width 0.1)
				(type default)
			)
			(layer "F.Fab")
		)
		(fp_line
			(start 0.299974 -0.150114)
			(end 0.299974 0.150114)
			(stroke
				(width 0.1)
				(type default)
			)
			(layer "F.Fab")
		)
		(fp_line
			(start -0.299974 0.150114)
			(end -0.299974 -0.150114)
			(stroke
				(width 0.1)
				(type default)
			)
			(layer "F.Fab")
		)
		(fp_line
			(start -0.299974 -0.150114)
			(end 0.299974 -0.150114)
			(stroke
				(width 0.1)
				(type default)
			)
			(layer "F.Fab")
		)
		(pad "1" smd rect
			(at -0.2667 0 180)
			(size 0.3048 0.381)
			(layers "F.Cu" "F.Mask" "F.Paste")
			(net "P5E_PEX3_STN2_TX_DN<37>")
		)
		(pad "2" smd rect
			(at 0.2667 0 180)
			(size 0.3048 0.381)
			(layers "F.Cu" "F.Mask" "F.Paste")
			(net "P5E_PEX3_STN2_TX_C_DN<37>")
		)
	)
	(footprint ""
		(layer "F.Cu")
		(at 234.949746 -120.381268 90)
		(property "Reference" "R5833"
			(at 0 0 90)
			(layer "F.SilkS")
			(hide yes)
			(effects
				(font
					(size 1.27 1.27)
				)
			)
		)
		(property "Value" ""
			(at 0 0 90)
			(layer "F.Fab")
			(effects
				(font
					(size 1.27 1.27)
				)
			)
		)
		(duplicate_pad_numbers_are_jumpers no)
		(fp_line
			(start 0.7874 -0.4064)
			(end 0.7874 0.4064)
			(stroke
				(width 0.1524)
				(type default)
			)
			(layer "F.SilkS")
		)
		(fp_line
			(start -0.7874 -0.4064)
			(end 0.7874 -0.4064)
			(stroke
				(width 0.1524)
				(type default)
			)
			(layer "F.SilkS")
		)
		(fp_line
			(start 0.7874 0.4064)
			(end -0.7874 0.4064)
			(stroke
				(width 0.1524)
				(type default)
			)
			(layer "F.SilkS")
		)
		(fp_line
			(start -0.7874 0.4064)
			(end -0.7874 -0.4064)
			(stroke
				(width 0.1524)
				(type default)
			)
			(layer "F.SilkS")
		)
		(fp_line
			(start -0.12065 -0.305054)
			(end -0.12065 -0.2794)
			(stroke
				(width 0.1)
				(type default)
			)
			(layer "F.Fab")
		)
		(fp_line
			(start -0.67945 -0.305054)
			(end -0.12065 -0.305054)
			(stroke
				(width 0.1)
				(type default)
			)
			(layer "F.Fab")
		)
		(fp_line
			(start 0.67945 -0.3048)
			(end 0.67945 0.3048)
			(stroke
				(width 0.1)
				(type default)
			)
			(layer "F.Fab")
		)
		(fp_line
			(start 0.12065 -0.3048)
			(end 0.67945 -0.3048)
			(stroke
				(width 0.1)
				(type default)
			)
			(layer "F.Fab")
		)
		(fp_line
			(start 0.12065 -0.2794)
			(end 0.12065 -0.3048)
			(stroke
				(width 0.1)
				(type default)
			)
			(layer "F.Fab")
		)
		(fp_line
			(start -0.12065 -0.2794)
			(end 0.12065 -0.2794)
			(stroke
				(width 0.1)
				(type default)
			)
			(layer "F.Fab")
		)
		(fp_line
			(start 0.120396 0.2794)
			(end -0.12065 0.2794)
			(stroke
				(width 0.1)
				(type default)
			)
			(layer "F.Fab")
		)
		(fp_line
			(start -0.12065 0.2794)
			(end -0.12065 0.3048)
			(stroke
				(width 0.1)
				(type default)
			)
			(layer "F.Fab")
		)
		(fp_line
			(start 0.67945 0.3048)
			(end 0.120396 0.3048)
			(stroke
				(width 0.1)
				(type default)
			)
			(layer "F.Fab")
		)
		(fp_line
			(start 0.120396 0.3048)
			(end 0.120396 0.2794)
			(stroke
				(width 0.1)
				(type default)
			)
			(layer "F.Fab")
		)
		(fp_line
			(start -0.12065 0.3048)
			(end -0.67945 0.3048)
			(stroke
				(width 0.1)
				(type default)
			)
			(layer "F.Fab")
		)
		(fp_line
			(start -0.67945 0.3048)
			(end -0.67945 -0.305054)
			(stroke
				(width 0.1)
				(type default)
			)
			(layer "F.Fab")
		)
		(pad "1" smd circle
			(at -0.40005 0 90)
			(size 0 0)
			(layers "F.Cu" "F.Mask" "F.Paste")
			(net "PWRGD_P12V_NIC3_CO")
		)
		(pad "2" smd circle
			(at 0.40005 0 90)
			(size 0 0)
			(layers "F.Cu" "F.Mask" "F.Paste")
			(net "PWRGD_P12V_NIC3_R")
		)
	)
	(footprint ""
		(layer "F.Cu")
		(at 212.047074 -55.63489 90)
		(property "Reference" "PC856"
			(at 0 0 90)
			(layer "F.SilkS")
			(hide yes)
			(effects
				(font
					(size 1.27 1.27)
				)
			)
		)
		(property "Value" ""
			(at 0 0 90)
			(layer "F.Fab")
			(effects
				(font
					(size 1.27 1.27)
				)
			)
		)
		(duplicate_pad_numbers_are_jumpers no)
		(fp_line
			(start 1.524 -0.762)
			(end 1.524 0.762)
			(stroke
				(width 0.1524)
				(type default)
			)
			(layer "F.SilkS")
		)
		(fp_line
			(start -1.524 -0.762)
			(end 1.524 -0.762)
			(stroke
				(width 0.1524)
				(type default)
			)
			(layer "F.SilkS")
		)
		(fp_line
			(start 1.524 0.762)
			(end -1.524 0.762)
			(stroke
				(width 0.1524)
				(type default)
			)
			(layer "F.SilkS")
		)
		(fp_line
			(start -1.524 0.762)
			(end -1.524 -0.762)
			(stroke
				(width 0.1524)
				(type default)
			)
			(layer "F.SilkS")
		)
		(fp_line
			(start 1.1049 -0.724916)
			(end -1.1049 -0.724916)
			(stroke
				(width 0.1)
				(type default)
			)
			(layer "F.Fab")
		)
		(fp_line
			(start -1.1049 -0.724916)
			(end -1.1049 0.724916)
			(stroke
				(width 0.1)
				(type default)
			)
			(layer "F.Fab")
		)
		(fp_line
			(start 1.1049 0.724916)
			(end 1.1049 -0.724916)
			(stroke
				(width 0.1)
				(type default)
			)
			(layer "F.Fab")
		)
		(fp_line
			(start -1.1049 0.724916)
			(end 1.1049 0.724916)
			(stroke
				(width 0.1)
				(type default)
			)
			(layer "F.Fab")
		)
		(pad "1" smd rect
			(at -0.889 0 270)
			(size 1.016 1.27)
			(layers "F.Cu" "F.Mask" "F.Paste")
			(net "P12V_SSD7_R")
		)
		(pad "2" smd rect
			(at 0.889 0 270)
			(size 1.016 1.27)
			(layers "F.Cu" "F.Mask" "F.Paste")
			(net "GND")
		)
	)
	(footprint ""
		(layer "F.Cu")
		(at 38.608 -162.044126 180)
		(property "Reference" "R22"
			(at 0 0 180)
			(layer "F.SilkS")
			(hide yes)
			(effects
				(font
					(size 1.27 1.27)
				)
			)
		)
		(property "Value" ""
			(at 0 0 180)
			(layer "F.Fab")
			(effects
				(font
					(size 1.27 1.27)
				)
			)
		)
		(duplicate_pad_numbers_are_jumpers no)
		(fp_line
			(start 0.7874 0.4064)
			(end -0.7874 0.4064)
			(stroke
				(width 0.1524)
				(type default)
			)
			(layer "F.SilkS")
		)
		(fp_line
			(start 0.7874 -0.4064)
			(end 0.7874 0.4064)
			(stroke
				(width 0.1524)
				(type default)
			)
			(layer "F.SilkS")
		)
		(fp_line
			(start -0.7874 0.4064)
			(end -0.7874 -0.4064)
			(stroke
				(width 0.1524)
				(type default)
			)
			(layer "F.SilkS")
		)
		(fp_line
			(start -0.7874 -0.4064)
			(end 0.7874 -0.4064)
			(stroke
				(width 0.1524)
				(type default)
			)
			(layer "F.SilkS")
		)
		(fp_line
			(start 0.67945 0.3048)
			(end 0.120396 0.3048)
			(stroke
				(width 0.1)
				(type default)
			)
			(layer "F.Fab")
		)
		(fp_line
			(start 0.67945 -0.3048)
			(end 0.67945 0.3048)
			(stroke
				(width 0.1)
				(type default)
			)
			(layer "F.Fab")
		)
		(fp_line
			(start 0.12065 -0.2794)
			(end 0.12065 -0.3048)
			(stroke
				(width 0.1)
				(type default)
			)
			(layer "F.Fab")
		)
		(fp_line
			(start 0.12065 -0.3048)
			(end 0.67945 -0.3048)
			(stroke
				(width 0.1)
				(type default)
			)
			(layer "F.Fab")
		)
		(fp_line
			(start 0.120396 0.3048)
			(end 0.120396 0.2794)
			(stroke
				(width 0.1)
				(type default)
			)
			(layer "F.Fab")
		)
		(fp_line
			(start 0.120396 0.2794)
			(end -0.12065 0.2794)
			(stroke
				(width 0.1)
				(type default)
			)
			(layer "F.Fab")
		)
		(fp_line
			(start -0.12065 0.3048)
			(end -0.67945 0.3048)
			(stroke
				(width 0.1)
				(type default)
			)
			(layer "F.Fab")
		)
		(fp_line
			(start -0.12065 0.2794)
			(end -0.12065 0.3048)
			(stroke
				(width 0.1)
				(type default)
			)
			(layer "F.Fab")
		)
		(fp_line
			(start -0.12065 -0.2794)
			(end 0.12065 -0.2794)
			(stroke
				(width 0.1)
				(type default)
			)
			(layer "F.Fab")
		)
		(fp_line
			(start -0.12065 -0.305054)
			(end -0.12065 -0.2794)
			(stroke
				(width 0.1)
				(type default)
			)
			(layer "F.Fab")
		)
		(fp_line
			(start -0.67945 0.3048)
			(end -0.67945 -0.305054)
			(stroke
				(width 0.1)
				(type default)
			)
			(layer "F.Fab")
		)
		(fp_line
			(start -0.67945 -0.305054)
			(end -0.12065 -0.305054)
			(stroke
				(width 0.1)
				(type default)
			)
			(layer "F.Fab")
		)
		(pad "1" smd circle
			(at -0.40005 0 180)
			(size 0 0)
			(layers "F.Cu" "F.Mask" "F.Paste")
			(net "PWRGD_NIC0_PWR_GOOD")
		)
		(pad "2" smd circle
			(at 0.40005 0 180)
			(size 0 0)
			(layers "F.Cu" "F.Mask" "F.Paste")
			(net "GND")
		)
	)
	(footprint ""
		(layer "F.Cu")
		(at 452.543672 -43.85691)
		(property "Reference" "R673"
			(at 0 0 0)
			(layer "F.SilkS")
			(hide yes)
			(effects
				(font
					(size 1.27 1.27)
				)
			)
		)
		(property "Value" ""
			(at 0 0 0)
			(layer "F.Fab")
			(effects
				(font
					(size 1.27 1.27)
				)
			)
		)
		(duplicate_pad_numbers_are_jumpers no)
		(fp_line
			(start -0.7874 -0.4064)
			(end 0.7874 -0.4064)
			(stroke
				(width 0.1524)
				(type default)
			)
			(layer "F.SilkS")
		)
		(fp_line
			(start -0.7874 0.4064)
			(end -0.7874 -0.4064)
			(stroke
				(width 0.1524)
				(type default)
			)
			(layer "F.SilkS")
		)
		(fp_line
			(start 0.7874 -0.4064)
			(end 0.7874 0.4064)
			(stroke
				(width 0.1524)
				(type default)
			)
			(layer "F.SilkS")
		)
		(fp_line
			(start 0.7874 0.4064)
			(end -0.7874 0.4064)
			(stroke
				(width 0.1524)
				(type default)
			)
			(layer "F.SilkS")
		)
		(fp_line
			(start -0.67945 -0.305054)
			(end -0.12065 -0.305054)
			(stroke
				(width 0.1)
				(type default)
			)
			(layer "F.Fab")
		)
		(fp_line
			(start -0.67945 0.3048)
			(end -0.67945 -0.305054)
			(stroke
				(width 0.1)
				(type default)
			)
			(layer "F.Fab")
		)
		(fp_line
			(start -0.12065 -0.305054)
			(end -0.12065 -0.2794)
			(stroke
				(width 0.1)
				(type default)
			)
			(layer "F.Fab")
		)
		(fp_line
			(start -0.12065 -0.2794)
			(end 0.12065 -0.2794)
			(stroke
				(width 0.1)
				(type default)
			)
			(layer "F.Fab")
		)
		(fp_line
			(start -0.12065 0.2794)
			(end -0.12065 0.3048)
			(stroke
				(width 0.1)
				(type default)
			)
			(layer "F.Fab")
		)
		(fp_line
			(start -0.12065 0.3048)
			(end -0.67945 0.3048)
			(stroke
				(width 0.1)
				(type default)
			)
			(layer "F.Fab")
		)
		(fp_line
			(start 0.120396 0.2794)
			(end -0.12065 0.2794)
			(stroke
				(width 0.1)
				(type default)
			)
			(layer "F.Fab")
		)
		(fp_line
			(start 0.120396 0.3048)
			(end 0.120396 0.2794)
			(stroke
				(width 0.1)
				(type default)
			)
			(layer "F.Fab")
		)
		(fp_line
			(start 0.12065 -0.3048)
			(end 0.67945 -0.3048)
			(stroke
				(width 0.1)
				(type default)
			)
			(layer "F.Fab")
		)
		(fp_line
			(start 0.12065 -0.2794)
			(end 0.12065 -0.3048)
			(stroke
				(width 0.1)
				(type default)
			)
			(layer "F.Fab")
		)
		(fp_line
			(start 0.67945 -0.3048)
			(end 0.67945 0.3048)
			(stroke
				(width 0.1)
				(type default)
			)
			(layer "F.Fab")
		)
		(fp_line
			(start 0.67945 0.3048)
			(end 0.120396 0.3048)
			(stroke
				(width 0.1)
				(type default)
			)
			(layer "F.Fab")
		)
		(pad "1" smd circle
			(at -0.40005 0)
			(size 0 0)
			(layers "F.Cu" "F.Mask" "F.Paste")
			(net "SSD15_ADC_A1")
		)
		(pad "2" smd circle
			(at 0.40005 0)
			(size 0 0)
			(layers "F.Cu" "F.Mask" "F.Paste")
			(net "GND")
		)
	)
)
